# SCM (Grand Teton) — schematic netlist excerpt (pin names and nets, part order shuffled) for the footprints in the layout excerpt that follows; sources: Cadence DE-HDL packaged netlist, KiCad conversion of 12092022_DA0F0TMDCD0_F0T_Management_Board_D_brd_V3_OCP.brd

H9  HOLE  EMPTY  pkg TH  page 57 : \1\ = GND
R551  Q_RES  33.2 1% CHIP  pkg 0402LF  page 25 : A = FLASH_WP_STATUS ; B = FLASH_R_WP_STATUS
R446  Q_RES  4.7K 1% CHIP  pkg 0402LF  page 13 : A = P3V3_AUX ; B = FM_PECI_SEL_N

(kicad_pcb
	(version 20260206)
	(generator "pcbnew")
	(generator_version "10.0")
	(general
		(thickness 1.6)
		(legacy_teardrops no)
	)
	(paper "A4")
	(title_block
		(title "12092022_DA0F0TMDCD0_F0T_Management_Board_D_brd_V3_OCP.brd")
		(comment 1 "Grand Teton / footprints 351-353 of 1440")
	)
	(layers
		(0 "F.Cu" signal "TOP")
		(4 "In1.Cu" signal "GND")
		(6 "In2.Cu" signal "IN1")
		(8 "In3.Cu" signal "GND1")
		(10 "In4.Cu" signal "IN2")
		(12 "In5.Cu" signal "VCC")
		(14 "In6.Cu" signal "VCC1")
		(16 "In7.Cu" signal "IN3")
		(18 "In8.Cu" signal "GND2")
		(20 "In9.Cu" signal "IN4")
		(22 "In10.Cu" signal "GND3")
		(2 "B.Cu" signal "BOTTOM")
		(9 "F.Adhes" user "F.Adhesive")
		(11 "B.Adhes" user "B.Adhesive")
		(13 "F.Paste" user "Package Geometry/Pastemask Top")
		(15 "B.Paste" user "Package Geometry/Pastemask Bottom")
		(5 "F.SilkS" user "Ref Des/Silkscreen Top")
		(7 "B.SilkS" user "Ref Des/Silkscreen Bottom")
		(1 "F.Mask" user "Board Geometry/Soldermask Top")
		(3 "B.Mask" user "Board Geometry/Soldermask Bottom")
		(17 "Dwgs.User" user "User.Drawings")
		(19 "Cmts.User" user "User.Comments")
		(21 "Eco1.User" user "User.Eco1")
		(23 "Eco2.User" user "User.Eco2")
		(25 "Edge.Cuts" user "Board Geometry/Outline")
		(27 "Margin" user)
		(31 "F.CrtYd" user "Package Geometry/Place Bound Top")
		(29 "B.CrtYd" user "Package Geometry/Place Bound Bottom")
		(35 "F.Fab" user "Ref Des/Assembly Top")
		(33 "B.Fab" user "Ref Des/Assembly Bottom")
	)
	(footprint ""
		(layer "F.Cu")
		(at 12.319 -84.328)
		(property "Reference" "R446"
			(at 0 0 0)
			(layer "F.SilkS")
			(hide yes)
			(effects
				(font
					(size 1.27 1.27)
				)
			)
		)
		(property "Value" ""
			(at 0 0 0)
			(layer "F.Fab")
			(effects
				(font
					(size 1.27 1.27)
				)
			)
		)
		(duplicate_pad_numbers_are_jumpers no)
		(fp_line
			(start -0.7874 -0.4064)
			(end 0.7874 -0.4064)
			(stroke
				(width 0.1524)
				(type default)
			)
			(layer "F.SilkS")
		)
		(fp_line
			(start -0.7874 0.4064)
			(end -0.7874 -0.4064)
			(stroke
				(width 0.1524)
				(type default)
			)
			(layer "F.SilkS")
		)
		(fp_line
			(start 0.7874 -0.4064)
			(end 0.7874 0.4064)
			(stroke
				(width 0.1524)
				(type default)
			)
			(layer "F.SilkS")
		)
		(fp_line
			(start 0.7874 0.4064)
			(end -0.7874 0.4064)
			(stroke
				(width 0.1524)
				(type default)
			)
			(layer "F.SilkS")
		)
		(fp_line
			(start -0.67945 -0.305054)
			(end -0.12065 -0.305054)
			(stroke
				(width 0.1)
				(type default)
			)
			(layer "F.Fab")
		)
		(fp_line
			(start -0.67945 0.3048)
			(end -0.67945 -0.305054)
			(stroke
				(width 0.1)
				(type default)
			)
			(layer "F.Fab")
		)
		(fp_line
			(start -0.12065 -0.305054)
			(end -0.12065 -0.2794)
			(stroke
				(width 0.1)
				(type default)
			)
			(layer "F.Fab")
		)
		(fp_line
			(start -0.12065 -0.2794)
			(end 0.12065 -0.2794)
			(stroke
				(width 0.1)
				(type default)
			)
			(layer "F.Fab")
		)
		(fp_line
			(start -0.12065 0.2794)
			(end -0.12065 0.3048)
			(stroke
				(width 0.1)
				(type default)
			)
			(layer "F.Fab")
		)
		(fp_line
			(start -0.12065 0.3048)
			(end -0.67945 0.3048)
			(stroke
				(width 0.1)
				(type default)
			)
			(layer "F.Fab")
		)
		(fp_line
			(start 0.120396 0.2794)
			(end -0.12065 0.2794)
			(stroke
				(width 0.1)
				(type default)
			)
			(layer "F.Fab")
		)
		(fp_line
			(start 0.120396 0.3048)
			(end 0.120396 0.2794)
			(stroke
				(width 0.1)
				(type default)
			)
			(layer "F.Fab")
		)
		(fp_line
			(start 0.12065 -0.3048)
			(end 0.67945 -0.3048)
			(stroke
				(width 0.1)
				(type default)
			)
			(layer "F.Fab")
		)
		(fp_line
			(start 0.12065 -0.2794)
			(end 0.12065 -0.3048)
			(stroke
				(width 0.1)
				(type default)
			)
			(layer "F.Fab")
		)
		(fp_line
			(start 0.67945 -0.3048)
			(end 0.67945 0.3048)
			(stroke
				(width 0.1)
				(type default)
			)
			(layer "F.Fab")
		)
		(fp_line
			(start 0.67945 0.3048)
			(end 0.120396 0.3048)
			(stroke
				(width 0.1)
				(type default)
			)
			(layer "F.Fab")
		)
		(pad "1" smd circle
			(at -0.40005 0)
			(size 0 0)
			(layers "F.Cu" "F.Mask" "F.Paste")
			(net "P3V3_AUX")
		)
		(pad "2" smd circle
			(at 0.40005 0)
			(size 0 0)
			(layers "F.Cu" "F.Mask" "F.Paste")
			(net "FM_PECI_SEL_N")
		)
	)
	(footprint ""
		(layer "F.Cu")
		(at 83.90001 -22.690074)
		(property "Reference" "H9"
			(at 3.474212 0.323596 0)
			(unlocked yes)
			(layer "F.SilkS")
			(effects
				(font
					(size 0.7874 0.5842)
					(thickness 0.1524)
				)
				(justify left)
			)
		)
		(property "Value" ""
			(at 0 0 0)
			(layer "F.Fab")
			(effects
				(font
					(size 1.27 1.27)
				)
			)
		)
		(duplicate_pad_numbers_are_jumpers no)
		(pad "1" thru_hole circle
			(at 0 0)
			(size 6.0452 6.0452)
			(drill 3.1496)
			(layers "*.Cu" "*.Mask")
			(remove_unused_layers no)
			(net "GND")
			(clearance -1.1938)
		)
	)
	(footprint ""
		(layer "F.Cu")
		(at 56.0324 -81.153 90)
		(property "Reference" "R551"
			(at 0 0 90)
			(layer "F.SilkS")
			(hide yes)
			(effects
				(font
					(size 1.27 1.27)
				)
			)
		)
		(property "Value" ""
			(at 0 0 90)
			(layer "F.Fab")
			(effects
				(font
					(size 1.27 1.27)
				)
			)
		)
		(duplicate_pad_numbers_are_jumpers no)
		(fp_line
			(start 0.7874 -0.4064)
			(end 0.7874 0.4064)
			(stroke
				(width 0.1524)
				(type default)
			)
			(layer "F.SilkS")
		)
		(fp_line
			(start -0.7874 -0.4064)
			(end 0.7874 -0.4064)
			(stroke
				(width 0.1524)
				(type default)
			)
			(layer "F.SilkS")
		)
		(fp_line
			(start 0.7874 0.4064)
			(end -0.7874 0.4064)
			(stroke
				(width 0.1524)
				(type default)
			)
			(layer "F.SilkS")
		)
		(fp_line
			(start -0.7874 0.4064)
			(end -0.7874 -0.4064)
			(stroke
				(width 0.1524)
				(type default)
			)
			(layer "F.SilkS")
		)
		(fp_line
			(start -0.12065 -0.305054)
			(end -0.12065 -0.2794)
			(stroke
				(width 0.1)
				(type default)
			)
			(layer "F.Fab")
		)
		(fp_line
			(start -0.67945 -0.305054)
			(end -0.12065 -0.305054)
			(stroke
				(width 0.1)
				(type default)
			)
			(layer "F.Fab")
		)
		(fp_line
			(start 0.67945 -0.3048)
			(end 0.67945 0.3048)
			(stroke
				(width 0.1)
				(type default)
			)
			(layer "F.Fab")
		)
		(fp_line
			(start 0.12065 -0.3048)
			(end 0.67945 -0.3048)
			(stroke
				(width 0.1)
				(type default)
			)
			(layer "F.Fab")
		)
		(fp_line
			(start 0.12065 -0.2794)
			(end 0.12065 -0.3048)
			(stroke
				(width 0.1)
				(type default)
			)
			(layer "F.Fab")
		)
		(fp_line
			(start -0.12065 -0.2794)
			(end 0.12065 -0.2794)
			(stroke
				(width 0.1)
				(type default)
			)
			(layer "F.Fab")
		)
		(fp_line
			(start 0.120396 0.2794)
			(end -0.12065 0.2794)
			(stroke
				(width 0.1)
				(type default)
			)
			(layer "F.Fab")
		)
		(fp_line
			(start -0.12065 0.2794)
			(end -0.12065 0.3048)
			(stroke
				(width 0.1)
				(type default)
			)
			(layer "F.Fab")
		)
		(fp_line
			(start 0.67945 0.3048)
			(end 0.120396 0.3048)
			(stroke
				(width 0.1)
				(type default)
			)
			(layer "F.Fab")
		)
		(fp_line
			(start 0.120396 0.3048)
			(end 0.120396 0.2794)
			(stroke
				(width 0.1)
				(type default)
			)
			(layer "F.Fab")
		)
		(fp_line
			(start -0.12065 0.3048)
			(end -0.67945 0.3048)
			(stroke
				(width 0.1)
				(type default)
			)
			(layer "F.Fab")
		)
		(fp_line
			(start -0.67945 0.3048)
			(end -0.67945 -0.305054)
			(stroke
				(width 0.1)
				(type default)
			)
			(layer "F.Fab")
		)
		(pad "1" smd circle
			(at -0.40005 0 90)
			(size 0 0)
			(layers "F.Cu" "F.Mask" "F.Paste")
			(net "FLASH_WP_STATUS")
		)
		(pad "2" smd circle
			(at 0.40005 0 90)
			(size 0 0)
			(layers "F.Cu" "F.Mask" "F.Paste")
			(net "FLASH_R_WP_STATUS")
		)
	)
)
